(kicad_pcb
	(version 20221018)
	(generator pcbnew)
	(general
    (thickness 1.586)
  )
	(paper "A4")
	(title_block
    (date "2024-03-26")
    (rev "1.1.3")
		(comment 9 "footprints 122-130 of 146")
	)
	(layers
    (0 "F.Cu" signal)
    (1 "In1.Cu" power)
    (2 "In2.Cu" power)
    (31 "B.Cu" signal)
    (32 "B.Adhes" user "B.Adhesive")
    (33 "F.Adhes" user "F.Adhesive")
    (34 "B.Paste" user)
    (35 "F.Paste" user)
    (36 "B.SilkS" user "B.Silkscreen")
    (37 "F.SilkS" user "F.Silkscreen")
    (38 "B.Mask" user)
    (39 "F.Mask" user)
    (40 "Dwgs.User" user "User.Drawings")
    (41 "Cmts.User" user "User.Comments")
    (42 "Eco1.User" user "User.Eco1")
    (43 "Eco2.User" user "User.Eco2")
    (44 "Edge.Cuts" user)
    (45 "Margin" user)
    (46 "B.CrtYd" user "B.Courtyard")
    (47 "F.CrtYd" user "F.Courtyard")
    (48 "B.Fab" user)
    (49 "F.Fab" user)
  )
	(footprint "scalenode-cm4-baseboard-footprints:C_0402_1005Metric" (layer "B.Cu")
    (at 101.233401 73.516445 -90)
    (descr "Capacitor SMD 0402")
    (tags "capacitor SMD 0402")
    (property "Author" "Antmicro")
    (property "Dielectric" "X7R")
    (property "License" "Apache-2.0")
    (property "MPN" "GRM155R71H103KA88D")
    (property "Manufacturer" "Murata")
    (property "Sheetfile" "poe.kicad_sch")
    (property "Sheetname" "PoE")
    (property "Val" "10n")
    (property "Voltage" "50V")
    (property "ki_description" " ")
    (attr smd)
    (fp_text reference "C27" (at -3.176445 -0.386599 -270) (layer "B.SilkS")
        (effects (font (size 0.7 0.7) (thickness 0.15)) (justify left bottom mirror))
    )
    (fp_text value "C_10n_0402" (at 0 -1.4 -270) (layer "B.Fab")
        (effects (font (size 0.7 0.7) (thickness 0.15)) (justify left bottom mirror))
    )
    (fp_text user "${REFERENCE}" (at -0.932 -3.168 -270) (layer "B.Fab") hide
        (effects (font (size 0.7 0.7) (thickness 0.15)) (justify left bottom mirror))
    )
    (fp_text user "Author: Antmicro" (at -0.932 -4.17 -270) (layer "B.Fab") hide
        (effects (font (size 0.7 0.7) (thickness 0.15)) (justify left bottom mirror))
    )
    (fp_text user "License: Apache-2.0" (at -0.932 -5.17 -270) (layer "B.Fab") hide
        (effects (font (size 0.7 0.7) (thickness 0.15)) (justify left bottom mirror))
    )
    (fp_rect (start -0.94 0.47) (end 0.94 -0.47)
      (stroke (width 0.05) (type solid)) (fill none) (layer "B.CrtYd"))
    (fp_rect (start -0.499 0.249) (end 0.499 -0.249)
      (stroke (width 0.15) (type solid)) (fill none) (layer "B.Fab"))
    (pad "1" smd roundrect (at -0.484 0 270) (size 0.59 0.64) (layers "B.Cu" "B.Paste" "B.Mask") (roundrect_rratio 0.25)
      (net 7 "Net-(C27-Pad1)") (pintype "passive"))
    (pad "2" smd roundrect (at 0.484 0 270) (size 0.59 0.64) (layers "B.Cu" "B.Paste" "B.Mask") (roundrect_rratio 0.25)
      (net 1 "/PoE/PAIR12") (pintype "passive"))
  )
	(footprint "scalenode-cm4-baseboard-footprints:C_0402_1005Metric" (layer "B.Cu")
    (at 102.8 64.506 180)
    (descr "Capacitor SMD 0402")
    (tags "capacitor SMD 0402")
    (property "Author" "Antmicro")
    (property "Dielectric" "X7R")
    (property "License" "Apache-2.0")
    (property "MPN" "GRM155R71H103KA88D")
    (property "Manufacturer" "Murata")
    (property "Sheetfile" "poe.kicad_sch")
    (property "Sheetname" "PoE")
    (property "Val" "10n")
    (property "Voltage" "50V")
    (property "ki_description" " ")
    (attr smd)
    (fp_text reference "C34" (at -1.15 0.731) (layer "B.SilkS")
        (effects (font (size 0.7 0.7) (thickness 0.15)) (justify left bottom mirror))
    )
    (fp_text value "C_10n_0402" (at 0 -1.4) (layer "B.Fab")
        (effects (font (size 0.7 0.7) (thickness 0.15)) (justify left bottom mirror))
    )
    (fp_text user "License: Apache-2.0" (at -0.932 -5.17) (layer "B.Fab") hide
        (effects (font (size 0.7 0.7) (thickness 0.15)) (justify left bottom mirror))
    )
    (fp_text user "${REFERENCE}" (at -0.932 -3.168) (layer "B.Fab") hide
        (effects (font (size 0.7 0.7) (thickness 0.15)) (justify left bottom mirror))
    )
    (fp_text user "Author: Antmicro" (at -0.932 -4.17) (layer "B.Fab") hide
        (effects (font (size 0.7 0.7) (thickness 0.15)) (justify left bottom mirror))
    )
    (fp_rect (start -0.94 0.47) (end 0.94 -0.47)
      (stroke (width 0.05) (type solid)) (fill none) (layer "B.CrtYd"))
    (fp_rect (start -0.499 0.249) (end 0.499 -0.249)
      (stroke (width 0.15) (type solid)) (fill none) (layer "B.Fab"))
    (pad "1" smd roundrect (at -0.484 0 180) (size 0.59 0.64) (layers "B.Cu" "B.Paste" "B.Mask") (roundrect_rratio 0.25)
      (net 14 "Net-(C34-Pad1)") (pintype "passive"))
    (pad "2" smd roundrect (at 0.484 0 180) (size 0.59 0.64) (layers "B.Cu" "B.Paste" "B.Mask") (roundrect_rratio 0.25)
      (net 20 "/PoE/PAIR78") (pintype "passive"))
  )
	(footprint "scalenode-cm4-baseboard-footprints:C_0402_1005Metric" (layer "B.Cu")
    (at 132 93.181 -90)
    (descr "Capacitor SMD 0402")
    (tags "capacitor SMD 0402")
    (property "Author" "Antmicro")
    (property "Dielectric" "X5R")
    (property "License" "Apache-2.0")
    (property "MPN" "GRM155R61H104KE14D")
    (property "Manufacturer" "Murata")
    (property "Sheetfile" "poe.kicad_sch")
    (property "Sheetname" "PoE")
    (property "Val" "100n")
    (property "Voltage" "50V")
    (property "ki_description" " ")
    (attr smd)
    (fp_text reference "C37" (at -0.981 0.65 90) (layer "B.SilkS")
        (effects (font (size 0.7 0.7) (thickness 0.15)) (justify left bottom mirror))
    )
    (fp_text value "C_100n_0402" (at -7.511 -0.28 90) (layer "B.Fab")
        (effects (font (size 0.7 0.7) (thickness 0.15)) (justify left bottom mirror))
    )
    (fp_text user "${REFERENCE}" (at -0.932 -3.168 90) (layer "B.Fab") hide
        (effects (font (size 0.7 0.7) (thickness 0.15)) (justify left bottom mirror))
    )
    (fp_text user "License: Apache-2.0" (at -0.932 -5.17 90) (layer "B.Fab") hide
        (effects (font (size 0.7 0.7) (thickness 0.15)) (justify left bottom mirror))
    )
    (fp_text user "Author: Antmicro" (at -0.932 -4.17 90) (layer "B.Fab") hide
        (effects (font (size 0.7 0.7) (thickness 0.15)) (justify left bottom mirror))
    )
    (fp_rect (start -0.94 0.47) (end 0.94 -0.47)
      (stroke (width 0.05) (type solid)) (fill none) (layer "B.CrtYd"))
    (fp_rect (start -0.499 0.249) (end 0.499 -0.249)
      (stroke (width 0.15) (type solid)) (fill none) (layer "B.Fab"))
    (pad "1" smd roundrect (at -0.484 0 270) (size 0.59 0.64) (layers "B.Cu" "B.Paste" "B.Mask") (roundrect_rratio 0.25)
      (net 11 "GND") (pintype "passive"))
    (pad "2" smd roundrect (at 0.484 0 270) (size 0.59 0.64) (layers "B.Cu" "B.Paste" "B.Mask") (roundrect_rratio 0.25)
      (net 13 "/PoE/VO5V") (pintype "passive"))
  )
	(footprint "scalenode-cm4-baseboard-footprints:F_1206_3216Metric" (layer "B.Cu")
    (at 127 91.896 180)
    (property "Author" "Antmicro")
    (property "License" "Apache-2.0")
    (property "MPN" "1206L450SLWR")
    (property "Manufacturer" "Littelfuse")
    (property "Sheetfile" "poe.kicad_sch")
    (property "Sheetname" "PoE")
    (property "ki_description" "POLY-FUSE LoRho Series, 6 VDC, 4.5 A")
    (property "ki_keywords" "fuse ptc pptc 1206L450SLWR")
    (attr smd)
    (fp_text reference "F1" (at -0.675 1.196) (layer "B.SilkS")
        (effects (font (size 0.7 0.7) (thickness 0.15)) (justify left bottom mirror))
    )
    (fp_text value "PTC_4.5A_1206" (at 0 -2) (layer "B.Fab")
        (effects (font (size 0.7 0.7) (thickness 0.15)) (justify left bottom mirror))
    )
    (fp_text user "License: Apache-2.0" (at -1.95 -5.2) (layer "B.Fab") hide
        (effects (font (size 0.7 0.7) (thickness 0.15)) (justify left bottom mirror))
    )
    (fp_text user "${REFERENCE}" (at -1.95 -4) (layer "B.Fab") hide
        (effects (font (size 0.7 0.7) (thickness 0.15)) (justify left bottom mirror))
    )
    (fp_text user "Author: Antmicro" (at -1.95 -6.4) (layer "B.Fab") hide
        (effects (font (size 0.7 0.7) (thickness 0.15)) (justify left bottom mirror))
    )
    (fp_line (start -0.413 -0.792) (end 0.36 -0.792)
      (stroke (width 0.15) (type solid)) (layer "B.SilkS"))
    (fp_line (start -0.413 0.861) (end 0.36 0.861)
      (stroke (width 0.15) (type solid)) (layer "B.SilkS"))
    (fp_rect (start -1.95 1) (end 1.95 -1)
      (stroke (width 0.05) (type solid)) (fill none) (layer "B.CrtYd"))
    (fp_line (start -1.677 -0.792) (end -1.677 0.861)
      (stroke (width 0.15) (type solid)) (layer "B.Fab"))
    (fp_line (start -1.677 0.861) (end 1.624 0.861)
      (stroke (width 0.15) (type solid)) (layer "B.Fab"))
    (fp_line (start 1.624 -0.792) (end -1.677 -0.792)
      (stroke (width 0.15) (type solid)) (layer "B.Fab"))
    (fp_line (start 1.624 0.861) (end 1.624 -0.792)
      (stroke (width 0.15) (type solid)) (layer "B.Fab"))
    (pad "1" smd rect (at -1.35 0 180) (size 1.143 2.032) (layers "B.Cu" "B.Paste" "B.Mask")
      (net 13 "/PoE/VO5V") (pintype "passive"))
    (pad "2" smd rect (at 1.35 0 180) (size 1.143 2.032) (layers "B.Cu" "B.Paste" "B.Mask")
      (net 12 "VCC5V0") (pintype "passive"))
  )
	(footprint "scalenode-cm4-baseboard-footprints:R_0402_1005Metric" (layer "B.Cu")
    (at 102.8 65.706)
    (descr "Resistor SMD 0402")
    (tags "resistor SMD 0402")
    (property "Author" "Antmicro")
    (property "License" "Apache-2.0")
    (property "MPN" "CR0402-FX-75R0GLF")
    (property "Manufacturer" "Bourns")
    (property "Sheetfile" "poe.kicad_sch")
    (property "Sheetname" "PoE")
    (property "Tolerance" "1%")
    (property "Val" "75R")
    (property "ki_description" "75R resistor in 0402 package with 1% tolerance")
    (attr smd)
    (fp_text reference "R32" (at 3.05 0.769 180) (layer "B.SilkS")
        (effects (font (size 0.7 0.7) (thickness 0.15)) (justify left bottom mirror))
    )
    (fp_text value "R_75R_0402" (at 0 -1.4 180) (layer "B.Fab")
        (effects (font (size 0.7 0.7) (thickness 0.15)) (justify left bottom mirror))
    )
    (fp_text user "License: Apache-2.0" (at -0.95 -5.169 180) (layer "B.Fab") hide
        (effects (font (size 0.7 0.7) (thickness 0.15)) (justify left bottom mirror))
    )
    (fp_text user "Author: Antmicro" (at -0.95 -4.169 180) (layer "B.Fab") hide
        (effects (font (size 0.7 0.7) (thickness 0.15)) (justify left bottom mirror))
    )
    (fp_text user "${REFERENCE}" (at -0.95 -3.168 180) (layer "B.Fab") hide
        (effects (font (size 0.7 0.7) (thickness 0.15)) (justify left bottom mirror))
    )
    (fp_rect (start -0.95 0.48) (end 0.95 -0.48)
      (stroke (width 0.05) (type solid)) (fill none) (layer "B.CrtYd"))
    (fp_rect (start -0.5 0.25) (end 0.5 -0.25)
      (stroke (width 0.15) (type solid)) (fill none) (layer "B.Fab"))
    (pad "1" smd roundrect (at -0.485 0) (size 0.59 0.64) (layers "B.Cu" "B.Paste" "B.Mask") (roundrect_rratio 0.25)
      (net 14 "Net-(C34-Pad1)") (pintype "passive"))
    (pad "2" smd roundrect (at 0.485 0) (size 0.59 0.64) (layers "B.Cu" "B.Paste" "B.Mask") (roundrect_rratio 0.25)
      (net 8 "Net-(C31-Pad1)") (pintype "passive"))
  )
	(footprint "scalenode-cm4-baseboard-footprints:R_0603_1608Metric" (layer "B.Cu")
    (at 176.07 70.146 -90)
    (descr "Resistor SMD 0603")
    (tags "resistor SMD 0603")
    (property "Author" "Antmicro")
    (property "License" "Apache-2.0")
    (property "MPN" "CR0603-FX-1002ELF")
    (property "Manufacturer" "Bourns")
    (property "Sheetfile" "nvme-ssd.kicad_sch")
    (property "Sheetname" "NVMe SSD")
    (property "Tolerance" "1%")
    (property "Val" "10k")
    (property "ki_description" "10k resistor in 0603 package with 1% tolerance")
    (attr smd)
    (fp_text reference "R3" (at 1.428129 -0.405341 90) (layer "B.SilkS")
        (effects (font (size 0.7 0.7) (thickness 0.15)) (justify left bottom mirror))
    )
    (fp_text value "R_10k_0603" (at 0 -1.6 90) (layer "B.Fab")
        (effects (font (size 0.7 0.7) (thickness 0.15)) (justify left bottom mirror))
    )
    (fp_text user "License: Apache-2.0" (at -1.25 -5.9 90) (layer "B.Fab") hide
        (effects (font (size 0.7 0.7) (thickness 0.15)) (justify left bottom mirror))
    )
    (fp_text user "Author: Antmicro" (at -1.25 -4.9 90) (layer "B.Fab") hide
        (effects (font (size 0.7 0.7) (thickness 0.15)) (justify left bottom mirror))
    )
    (fp_text user "${REFERENCE}" (at -1.25 -3.898 90) (layer "B.Fab") hide
        (effects (font (size 0.7 0.7) (thickness 0.15)) (justify left bottom mirror))
    )
    (fp_line (start -0.3 -0.3) (end 0.3 -0.3)
      (stroke (width 0.15) (type solid)) (layer "B.SilkS"))
    (fp_line (start -0.3 0.3) (end 0.3 0.3)
      (stroke (width 0.15) (type solid)) (layer "B.SilkS"))
    (fp_rect (start -1.25 0.7) (end 1.25 -0.7)
      (stroke (width 0.05) (type solid)) (fill none) (layer "B.CrtYd"))
    (fp_rect (start -0.8 0.4) (end 0.8 -0.4)
      (stroke (width 0.15) (type solid)) (fill none) (layer "B.Fab"))
    (pad "1" smd roundrect (at -0.7 0 270) (size 0.6 0.8) (layers "B.Cu" "B.Paste" "B.Mask") (roundrect_rratio 0.2)
      (net 170 "3V3_SSD") (pintype "passive"))
    (pad "2" smd roundrect (at 0.7 0 270) (size 0.6 0.8) (layers "B.Cu" "B.Paste" "B.Mask") (roundrect_rratio 0.2)
      (net 96 "PCIE_CLK_nREQ") (pintype "passive"))
  )
	(footprint "scalenode-cm4-baseboard-footprints:C_0603_1608Metric" (layer "B.Cu")
    (at 133.3 93.496 -90)
    (descr "Capacitor SMD 0603")
    (tags "capacitor 0603")
    (property "Author" "Antmicro")
    (property "Dielectric" "")
    (property "License" "Apache-2.0")
    (property "MPN" "GRM188R60J476ME15D")
    (property "Manufacturer" "Murata")
    (property "Sheetfile" "poe.kicad_sch")
    (property "Sheetname" "PoE")
    (property "Val" "47u")
    (property "Voltage" "")
    (property "ki_description" " ")
    (attr smd)
    (fp_text reference "C35" (at 2.279 -1.125 180) (layer "B.SilkS")
        (effects (font (size 0.7 0.7) (thickness 0.15)) (justify left bottom mirror))
    )
    (fp_text value "C_47u_0603" (at -8.671 -1.705 90) (layer "B.Fab")
        (effects (font (size 0.7 0.7) (thickness 0.15)) (justify left bottom mirror))
    )
    (fp_text user "${REFERENCE}" (at -1.682 -3.895 90) (layer "B.Fab") hide
        (effects (font (size 0.7 0.7) (thickness 0.15)) (justify left bottom mirror))
    )
    (fp_text user "License: Apache-2.0" (at -1.682 -5.895 90) (layer "B.Fab") hide
        (effects (font (size 0.7 0.7) (thickness 0.15)) (justify left bottom mirror))
    )
    (fp_text user "Author: Antmicro" (at -1.682 -4.894 90) (layer "B.Fab") hide
        (effects (font (size 0.7 0.7) (thickness 0.15)) (justify left bottom mirror))
    )
    (fp_line (start -0.3 -0.3) (end 0.3 -0.3)
      (stroke (width 0.15) (type solid)) (layer "B.SilkS"))
    (fp_line (start -0.3 0.3) (end 0.3 0.3)
      (stroke (width 0.15) (type solid)) (layer "B.SilkS"))
    (fp_rect (start -1.24 0.7) (end 1.24 -0.7)
      (stroke (width 0.05) (type solid)) (fill none) (layer "B.CrtYd"))
    (fp_rect (start -0.8 0.4) (end 0.8 -0.4)
      (stroke (width 0.15) (type solid)) (fill none) (layer "B.Fab"))
    (pad "1" smd roundrect (at -0.7 0 270) (size 0.6 0.8) (layers "B.Cu" "B.Paste" "B.Mask") (roundrect_rratio 0.2)
      (net 11 "GND") (pintype "passive"))
    (pad "2" smd roundrect (at 0.7 0 270) (size 0.6 0.8) (layers "B.Cu" "B.Paste" "B.Mask") (roundrect_rratio 0.2)
      (net 13 "/PoE/VO5V") (pintype "passive"))
  )
	(footprint "scalenode-cm4-baseboard-footprints:R_0402_1005Metric" (layer "B.Cu")
    (at 102.8 68.206)
    (descr "Resistor SMD 0402")
    (tags "resistor SMD 0402")
    (property "Author" "Antmicro")
    (property "License" "Apache-2.0")
    (property "MPN" "CR0402-FX-75R0GLF")
    (property "Manufacturer" "Bourns")
    (property "Sheetfile" "poe.kicad_sch")
    (property "Sheetname" "PoE")
    (property "Tolerance" "1%")
    (property "Val" "75R")
    (property "ki_description" "75R resistor in 0402 package with 1% tolerance")
    (attr smd)
    (fp_text reference "R31" (at 3.05 0.344 180) (layer "B.SilkS")
        (effects (font (size 0.7 0.7) (thickness 0.15)) (justify left bottom mirror))
    )
    (fp_text value "R_75R_0402" (at 0 -1.4 180) (layer "B.Fab")
        (effects (font (size 0.7 0.7) (thickness 0.15)) (justify left bottom mirror))
    )
    (fp_text user "${REFERENCE}" (at -0.95 -3.168 180) (layer "B.Fab") hide
        (effects (font (size 0.7 0.7) (thickness 0.15)) (justify left bottom mirror))
    )
    (fp_text user "Author: Antmicro" (at -0.95 -4.169 180) (layer "B.Fab") hide
        (effects (font (size 0.7 0.7) (thickness 0.15)) (justify left bottom mirror))
    )
    (fp_text user "License: Apache-2.0" (at -0.95 -5.169 180) (layer "B.Fab") hide
        (effects (font (size 0.7 0.7) (thickness 0.15)) (justify left bottom mirror))
    )
    (fp_rect (start -0.95 0.48) (end 0.95 -0.48)
      (stroke (width 0.05) (type solid)) (fill none) (layer "B.CrtYd"))
    (fp_rect (start -0.5 0.25) (end 0.5 -0.25)
      (stroke (width 0.15) (type solid)) (fill none) (layer "B.Fab"))
    (pad "1" smd roundrect (at -0.485 0) (size 0.59 0.64) (layers "B.Cu" "B.Paste" "B.Mask") (roundrect_rratio 0.25)
      (net 10 "Net-(C33-Pad1)") (pintype "passive"))
    (pad "2" smd roundrect (at 0.485 0) (size 0.59 0.64) (layers "B.Cu" "B.Paste" "B.Mask") (roundrect_rratio 0.25)
      (net 8 "Net-(C31-Pad1)") (pintype "passive"))
  )
	(footprint "scalenode-cm4-baseboard-footprints:C_1210_3225Metric" (layer "B.Cu")
    (at 98 59.506 180)
    (descr "Capacitor SMD 1210")
    (tags "capacitor SMD 1210")
    (property "Author" "Antmicro")
    (property "Dielectric" "")
    (property "License" "Apache-2.0")
    (property "MPN" "C1210C102KGRACTU")
    (property "Manufacturer" "KEMET")
    (property "Sheetfile" "poe.kicad_sch")
    (property "Sheetname" "PoE")
    (property "Val" "1n")
    (property "Voltage" "2kV")
    (property "ki_description" " ")
    (attr smd)
    (fp_text reference "C31" (at -1 1.756) (layer "B.SilkS")
        (effects (font (size 0.7 0.7) (thickness 0.15)) (justify left bottom mirror))
    )
    (fp_text value "C_1n_1210_2kV" (at 0 -2.749) (layer "B.Fab")
        (effects (font (size 0.7 0.7) (thickness 0.15)) (justify left bottom mirror))
    )
    (fp_text user "License: Apache-2.0" (at -2.1 -6.749) (layer "B.Fab") hide
        (effects (font (size 0.7 0.7) (thickness 0.15)) (justify left bottom mirror))
    )
    (fp_text user "Author: Antmicro" (at -2.1 -5.749) (layer "B.Fab") hide
        (effects (font (size 0.7 0.7) (thickness 0.15)) (justify left bottom mirror))
    )
    (fp_text user "${REFERENCE}" (at -2.1 -4.749) (layer "B.Fab") hide
        (effects (font (size 0.7 0.7) (thickness 0.15)) (justify left bottom mirror))
    )
    (fp_line (start -0.3 -1.39) (end 0.3 -1.39)
      (stroke (width 0.15) (type solid)) (layer "B.SilkS"))
    (fp_line (start -0.3 1.39) (end 0.3 1.39)
      (stroke (width 0.15) (type solid)) (layer "B.SilkS"))
    (fp_rect (start -2.1 1.75) (end 2.1 -1.75)
      (stroke (width 0.05) (type solid)) (fill none) (layer "B.CrtYd"))
    (fp_rect (start -1.6 1.25) (end 1.6 -1.25)
      (stroke (width 0.15) (type solid)) (fill none) (layer "B.Fab"))
    (pad "1" smd rect (at -1.145 0 180) (size 1.52 3.05) (layers "B.Cu" "B.Paste" "B.Mask")
      (net 8 "Net-(C31-Pad1)") (pintype "passive"))
    (pad "2" smd rect (at 1.145 0 180) (size 1.52 3.05) (layers "B.Cu" "B.Paste" "B.Mask")
      (net 230 "Earth") (pintype "passive"))
  )
)
